# T6G (Grand Teton) — schematic netlist excerpt (pin names and nets, part order shuffled) for the footprints in the layout excerpt that follows; sources: Cadence DE-HDL packaged netlist, KiCad conversion of 04192023_DAF0TMB3IC0_F0TG_MB_C_brd_V02_OCP.brd

PC2158  Q_CAP  2.2UF 16V 20% X7R  pkg C0603  page 135 : A = P12V_OCP_AVIN_PD_1 ; B = GND
R1023  Q_RES  4.7K 5% EMPTY  pkg 0201LF  page 287 : A = P1V8_CPU0_RT_1D ; B = RST_RT_CPU0_P1_RESET_R_N
PC2152  Q_CAP  0.1UF 25V 10% X7R  pkg 0402  page 140 : A = P12V_OCP_V3_2 ; B = GND

(kicad_pcb
	(version 20260206)
	(generator "pcbnew")
	(generator_version "10.0")
	(general
		(thickness 1.6)
		(legacy_teardrops no)
	)
	(paper "A4")
	(title_block
		(title "04192023_DAF0TMB3IC0_F0TG_MB_C_brd_V02_OCP.brd")
		(comment 1 "Grand Teton / footprints 1312-1314 of 8354")
	)
	(layers
		(0 "F.Cu" signal "TOP")
		(4 "In1.Cu" signal "GND")
		(6 "In2.Cu" signal "IN1")
		(8 "In3.Cu" signal "GND1")
		(10 "In4.Cu" signal "IN2")
		(12 "In5.Cu" signal "GND2")
		(14 "In6.Cu" signal "IN3")
		(16 "In7.Cu" signal "GND3")
		(18 "In8.Cu" signal "VCC")
		(20 "In9.Cu" signal "VCC1")
		(22 "In10.Cu" signal "GND4")
		(24 "In11.Cu" signal "IN4")
		(26 "In12.Cu" signal "GND5")
		(28 "In13.Cu" signal "IN5")
		(30 "In14.Cu" signal "GND6")
		(32 "In15.Cu" signal "IN6")
		(34 "In16.Cu" signal "GND7")
		(2 "B.Cu" signal "BOTTOM")
		(9 "F.Adhes" user "F.Adhesive")
		(11 "B.Adhes" user "B.Adhesive")
		(13 "F.Paste" user "Package Geometry/Pastemask Top")
		(15 "B.Paste" user "Package Geometry/Pastemask Bottom")
		(5 "F.SilkS" user "Ref Des/Silkscreen Top")
		(7 "B.SilkS" user "Ref Des/Silkscreen Bottom")
		(1 "F.Mask" user "Board Geometry/Soldermask Top")
		(3 "B.Mask" user "Board Geometry/Soldermask Bottom")
		(17 "Dwgs.User" user "User.Drawings")
		(19 "Cmts.User" user "User.Comments")
		(21 "Eco1.User" user "User.Eco1")
		(23 "Eco2.User" user "User.Eco2")
		(25 "Edge.Cuts" user "Board Geometry/Outline")
		(27 "Margin" user)
		(31 "F.CrtYd" user "Package Geometry/Place Bound Top")
		(29 "B.CrtYd" user "Package Geometry/Place Bound Bottom")
		(35 "F.Fab" user "Ref Des/Assembly Top")
		(33 "B.Fab" user "Ref Des/Assembly Bottom")
	)
	(footprint ""
		(layer "F.Cu")
		(at 65.1002 -18.6436 180)
		(property "Reference" "PC2152"
			(at 0 0 180)
			(layer "F.SilkS")
			(hide yes)
			(effects
				(font
					(size 1.27 1.27)
				)
			)
		)
		(property "Value" ""
			(at 0 0 180)
			(layer "F.Fab")
			(effects
				(font
					(size 1.27 1.27)
				)
			)
		)
		(duplicate_pad_numbers_are_jumpers no)
		(fp_line
			(start 0.7874 0.4064)
			(end -0.7874 0.4064)
			(stroke
				(width 0.1524)
				(type default)
			)
			(layer "F.SilkS")
		)
		(fp_line
			(start 0.7874 -0.4064)
			(end 0.7874 0.4064)
			(stroke
				(width 0.1524)
				(type default)
			)
			(layer "F.SilkS")
		)
		(fp_line
			(start -0.7874 0.4064)
			(end -0.7874 -0.4064)
			(stroke
				(width 0.1524)
				(type default)
			)
			(layer "F.SilkS")
		)
		(fp_line
			(start -0.7874 -0.4064)
			(end 0.7874 -0.4064)
			(stroke
				(width 0.1524)
				(type default)
			)
			(layer "F.SilkS")
		)
		(fp_line
			(start 0.67945 0.3048)
			(end 0.120396 0.3048)
			(stroke
				(width 0.1)
				(type default)
			)
			(layer "F.Fab")
		)
		(fp_line
			(start 0.67945 -0.3048)
			(end 0.67945 0.3048)
			(stroke
				(width 0.1)
				(type default)
			)
			(layer "F.Fab")
		)
		(fp_line
			(start 0.12065 -0.2794)
			(end 0.12065 -0.3048)
			(stroke
				(width 0.1)
				(type default)
			)
			(layer "F.Fab")
		)
		(fp_line
			(start 0.12065 -0.3048)
			(end 0.67945 -0.3048)
			(stroke
				(width 0.1)
				(type default)
			)
			(layer "F.Fab")
		)
		(fp_line
			(start 0.120396 0.3048)
			(end 0.120396 0.2794)
			(stroke
				(width 0.1)
				(type default)
			)
			(layer "F.Fab")
		)
		(fp_line
			(start 0.120396 0.2794)
			(end -0.12065 0.2794)
			(stroke
				(width 0.1)
				(type default)
			)
			(layer "F.Fab")
		)
		(fp_line
			(start -0.12065 0.3048)
			(end -0.67945 0.3048)
			(stroke
				(width 0.1)
				(type default)
			)
			(layer "F.Fab")
		)
		(fp_line
			(start -0.12065 0.2794)
			(end -0.12065 0.3048)
			(stroke
				(width 0.1)
				(type default)
			)
			(layer "F.Fab")
		)
		(fp_line
			(start -0.12065 -0.2794)
			(end 0.12065 -0.2794)
			(stroke
				(width 0.1)
				(type default)
			)
			(layer "F.Fab")
		)
		(fp_line
			(start -0.12065 -0.305054)
			(end -0.12065 -0.2794)
			(stroke
				(width 0.1)
				(type default)
			)
			(layer "F.Fab")
		)
		(fp_line
			(start -0.67945 0.3048)
			(end -0.67945 -0.305054)
			(stroke
				(width 0.1)
				(type default)
			)
			(layer "F.Fab")
		)
		(fp_line
			(start -0.67945 -0.305054)
			(end -0.12065 -0.305054)
			(stroke
				(width 0.1)
				(type default)
			)
			(layer "F.Fab")
		)
		(pad "1" smd circle
			(at -0.40005 0 180)
			(size 0 0)
			(layers "F.Cu" "F.Mask" "F.Paste")
			(net "P12V_OCP_V3_2")
		)
		(pad "2" smd circle
			(at 0.40005 0 180)
			(size 0 0)
			(layers "F.Cu" "F.Mask" "F.Paste")
			(net "GND")
		)
	)
	(footprint ""
		(layer "F.Cu")
		(at 439.295032 -25.330658 180)
		(property "Reference" "PC2158"
			(at 0 0 180)
			(layer "F.SilkS")
			(hide yes)
			(effects
				(font
					(size 1.27 1.27)
				)
			)
		)
		(property "Value" ""
			(at 0 0 180)
			(layer "F.Fab")
			(effects
				(font
					(size 1.27 1.27)
				)
			)
		)
		(duplicate_pad_numbers_are_jumpers no)
		(fp_line
			(start 1.2954 0.5842)
			(end -1.2954 0.5842)
			(stroke
				(width 0.1524)
				(type default)
			)
			(layer "F.SilkS")
		)
		(fp_line
			(start 1.2954 -0.5842)
			(end 1.2954 0.5842)
			(stroke
				(width 0.1524)
				(type default)
			)
			(layer "F.SilkS")
		)
		(fp_line
			(start -1.2954 0.5842)
			(end -1.2954 -0.5842)
			(stroke
				(width 0.1524)
				(type default)
			)
			(layer "F.SilkS")
		)
		(fp_line
			(start -1.2954 -0.5842)
			(end 1.2954 -0.5842)
			(stroke
				(width 0.1524)
				(type default)
			)
			(layer "F.SilkS")
		)
		(fp_line
			(start 1.1938 0.4064)
			(end 0.8636 0.4064)
			(stroke
				(width 0.1)
				(type default)
			)
			(layer "F.Fab")
		)
		(fp_line
			(start 1.1938 -0.4064)
			(end 1.1938 0.4064)
			(stroke
				(width 0.1)
				(type default)
			)
			(layer "F.Fab")
		)
		(fp_line
			(start 0.8636 0.4572)
			(end -0.8636 0.4572)
			(stroke
				(width 0.1)
				(type default)
			)
			(layer "F.Fab")
		)
		(fp_line
			(start 0.8636 0.4064)
			(end 0.8636 0.4572)
			(stroke
				(width 0.1)
				(type default)
			)
			(layer "F.Fab")
		)
		(fp_line
			(start 0.8636 -0.4064)
			(end 1.1938 -0.4064)
			(stroke
				(width 0.1)
				(type default)
			)
			(layer "F.Fab")
		)
		(fp_line
			(start 0.8636 -0.4572)
			(end 0.8636 -0.4064)
			(stroke
				(width 0.1)
				(type default)
			)
			(layer "F.Fab")
		)
		(fp_line
			(start -0.8636 0.4572)
			(end -0.8636 0.4064)
			(stroke
				(width 0.1)
				(type default)
			)
			(layer "F.Fab")
		)
		(fp_line
			(start -0.8636 0.4064)
			(end -1.1938 0.4064)
			(stroke
				(width 0.1)
				(type default)
			)
			(layer "F.Fab")
		)
		(fp_line
			(start -0.8636 -0.4064)
			(end -0.8636 -0.4572)
			(stroke
				(width 0.1)
				(type default)
			)
			(layer "F.Fab")
		)
		(fp_line
			(start -0.8636 -0.4572)
			(end 0.8636 -0.4572)
			(stroke
				(width 0.1)
				(type default)
			)
			(layer "F.Fab")
		)
		(fp_line
			(start -1.1938 0.4064)
			(end -1.1938 -0.4064)
			(stroke
				(width 0.1)
				(type default)
			)
			(layer "F.Fab")
		)
		(fp_line
			(start -1.1938 -0.4064)
			(end -0.8636 -0.4064)
			(stroke
				(width 0.1)
				(type default)
			)
			(layer "F.Fab")
		)
		(pad "1" smd rect
			(at -0.7366 0 90)
			(size 0.7112 0.8128)
			(layers "F.Cu" "F.Mask" "F.Paste")
			(net "P12V_OCP_AVIN_PD_1")
		)
		(pad "2" smd rect
			(at 0.7366 0 90)
			(size 0.7112 0.8128)
			(layers "F.Cu" "F.Mask" "F.Paste")
			(net "GND")
		)
	)
	(footprint ""
		(layer "F.Cu")
		(at 333.215488 -403.818852 -90)
		(property "Reference" "R1023"
			(at 0 0 270)
			(layer "F.SilkS")
			(hide yes)
			(effects
				(font
					(size 1.27 1.27)
				)
			)
		)
		(property "Value" ""
			(at 0 0 270)
			(layer "F.Fab")
			(effects
				(font
					(size 1.27 1.27)
				)
			)
		)
		(duplicate_pad_numbers_are_jumpers no)
		(fp_line
			(start -0.32512 0.175006)
			(end -0.32512 -0.175006)
			(stroke
				(width 0.1)
				(type default)
			)
			(layer "F.Fab")
		)
		(fp_line
			(start 0.32512 0.175006)
			(end -0.32512 0.175006)
			(stroke
				(width 0.1)
				(type default)
			)
			(layer "F.Fab")
		)
		(fp_line
			(start -0.32512 -0.175006)
			(end 0.32512 -0.175006)
			(stroke
				(width 0.1)
				(type default)
			)
			(layer "F.Fab")
		)
		(fp_line
			(start 0.32512 -0.175006)
			(end 0.32512 0.175006)
			(stroke
				(width 0.1)
				(type default)
			)
			(layer "F.Fab")
		)
		(pad "1" smd rect
			(at -0.2667 0 270)
			(size 0.3048 0.381)
			(layers "F.Cu" "F.Mask" "F.Paste")
			(net "P1V8_CPU0_RT_1D")
		)
		(pad "2" smd rect
			(at 0.2667 0 90)
			(size 0.3048 0.381)
			(layers "F.Cu" "F.Mask" "F.Paste")
			(net "RST_RT_CPU0_P1_RESET_R_N")
		)
	)
)
